(kicad_pcb
	(version 20260206)
	(generator "pcbnew")
	(generator_version "10.0")
	(general
		(thickness 1.6)
		(legacy_teardrops no)
	)
	(paper "A4")
	(title_block
		(title "01162023_DA0F0TEBIF0_F0T_Expander_BD_F_brd_V02_OCP.brd")
		(comment 1 "Grand Teton / footprints 4464-4469 of 9728")
	)
	(layers
		(0 "F.Cu" signal "TOP")
		(4 "In1.Cu" signal "GND")
		(6 "In2.Cu" signal "VCC")
		(8 "In3.Cu" signal "VCC1")
		(10 "In4.Cu" signal "GND1")
		(12 "In5.Cu" signal "IN1")
		(14 "In6.Cu" signal "GND2")
		(16 "In7.Cu" signal "IN2")
		(18 "In8.Cu" signal "GND3")
		(20 "In9.Cu" signal "IN3")
		(22 "In10.Cu" signal "GND4")
		(24 "In11.Cu" signal "IN4")
		(26 "In12.Cu" signal "GND5")
		(28 "In13.Cu" signal "IN5")
		(30 "In14.Cu" signal "GND6")
		(32 "In15.Cu" signal "IN6")
		(34 "In16.Cu" signal "GND7")
		(2 "B.Cu" signal "BOTTOM")
		(9 "F.Adhes" user "F.Adhesive")
		(11 "B.Adhes" user "B.Adhesive")
		(13 "F.Paste" user "Package Geometry/Pastemask Top")
		(15 "B.Paste" user "Package Geometry/Pastemask Bottom")
		(5 "F.SilkS" user "Ref Des/Silkscreen Top")
		(7 "B.SilkS" user "Ref Des/Silkscreen Bottom")
		(1 "F.Mask" user "Board Geometry/Soldermask Top")
		(3 "B.Mask" user "Board Geometry/Soldermask Bottom")
		(17 "Dwgs.User" user "User.Drawings")
		(19 "Cmts.User" user "User.Comments")
		(21 "Eco1.User" user "User.Eco1")
		(23 "Eco2.User" user "User.Eco2")
		(25 "Edge.Cuts" user "Board Geometry/Outline")
		(27 "Margin" user)
		(31 "F.CrtYd" user "Package Geometry/Place Bound Top")
		(29 "B.CrtYd" user "Package Geometry/Place Bound Bottom")
		(35 "F.Fab" user "Ref Des/Assembly Top")
		(33 "B.Fab" user "Ref Des/Assembly Bottom")
	)
	(footprint ""
		(layer "F.Cu")
		(at 143.938752 -311.156604 -90)
		(property "Reference" "R1263"
			(at 0 0 270)
			(layer "F.SilkS")
			(hide yes)
			(effects
				(font
					(size 1.27 1.27)
				)
			)
		)
		(property "Value" ""
			(at 0 0 270)
			(layer "F.Fab")
			(effects
				(font
					(size 1.27 1.27)
				)
			)
		)
		(duplicate_pad_numbers_are_jumpers no)
		(fp_line
			(start -0.7874 0.4064)
			(end -0.7874 -0.4064)
			(stroke
				(width 0.1524)
				(type default)
			)
			(layer "F.SilkS")
		)
		(fp_line
			(start 0.7874 0.4064)
			(end -0.7874 0.4064)
			(stroke
				(width 0.1524)
				(type default)
			)
			(layer "F.SilkS")
		)
		(fp_line
			(start -0.7874 -0.4064)
			(end 0.7874 -0.4064)
			(stroke
				(width 0.1524)
				(type default)
			)
			(layer "F.SilkS")
		)
		(fp_line
			(start 0.7874 -0.4064)
			(end 0.7874 0.4064)
			(stroke
				(width 0.1524)
				(type default)
			)
			(layer "F.SilkS")
		)
		(fp_line
			(start -0.67945 0.3048)
			(end -0.67945 -0.305054)
			(stroke
				(width 0.1)
				(type default)
			)
			(layer "F.Fab")
		)
		(fp_line
			(start -0.12065 0.3048)
			(end -0.67945 0.3048)
			(stroke
				(width 0.1)
				(type default)
			)
			(layer "F.Fab")
		)
		(fp_line
			(start 0.120396 0.3048)
			(end 0.120396 0.2794)
			(stroke
				(width 0.1)
				(type default)
			)
			(layer "F.Fab")
		)
		(fp_line
			(start 0.67945 0.3048)
			(end 0.120396 0.3048)
			(stroke
				(width 0.1)
				(type default)
			)
			(layer "F.Fab")
		)
		(fp_line
			(start -0.12065 0.2794)
			(end -0.12065 0.3048)
			(stroke
				(width 0.1)
				(type default)
			)
			(layer "F.Fab")
		)
		(fp_line
			(start 0.120396 0.2794)
			(end -0.12065 0.2794)
			(stroke
				(width 0.1)
				(type default)
			)
			(layer "F.Fab")
		)
		(fp_line
			(start -0.12065 -0.2794)
			(end 0.12065 -0.2794)
			(stroke
				(width 0.1)
				(type default)
			)
			(layer "F.Fab")
		)
		(fp_line
			(start 0.12065 -0.2794)
			(end 0.12065 -0.3048)
			(stroke
				(width 0.1)
				(type default)
			)
			(layer "F.Fab")
		)
		(fp_line
			(start 0.12065 -0.3048)
			(end 0.67945 -0.3048)
			(stroke
				(width 0.1)
				(type default)
			)
			(layer "F.Fab")
		)
		(fp_line
			(start 0.67945 -0.3048)
			(end 0.67945 0.3048)
			(stroke
				(width 0.1)
				(type default)
			)
			(layer "F.Fab")
		)
		(fp_line
			(start -0.67945 -0.305054)
			(end -0.12065 -0.305054)
			(stroke
				(width 0.1)
				(type default)
			)
			(layer "F.Fab")
		)
		(fp_line
			(start -0.12065 -0.305054)
			(end -0.12065 -0.2794)
			(stroke
				(width 0.1)
				(type default)
			)
			(layer "F.Fab")
		)
		(pad "1" smd circle
			(at -0.40005 0 270)
			(size 0 0)
			(layers "F.Cu" "F.Mask" "F.Paste")
			(net "PEX1_DBG_SEL1")
		)
		(pad "2" smd circle
			(at 0.40005 0 270)
			(size 0 0)
			(layers "F.Cu" "F.Mask" "F.Paste")
			(net "P1V8_PEX")
		)
	)
	(footprint ""
		(layer "F.Cu")
		(at 327.19137 -227.711 -90)
		(property "Reference" "R4384"
			(at 0 0 270)
			(layer "F.SilkS")
			(hide yes)
			(effects
				(font
					(size 1.27 1.27)
				)
			)
		)
		(property "Value" ""
			(at 0 0 270)
			(layer "F.Fab")
			(effects
				(font
					(size 1.27 1.27)
				)
			)
		)
		(duplicate_pad_numbers_are_jumpers no)
		(fp_line
			(start -0.7874 0.4064)
			(end -0.7874 -0.4064)
			(stroke
				(width 0.1524)
				(type default)
			)
			(layer "F.SilkS")
		)
		(fp_line
			(start 0.7874 0.4064)
			(end -0.7874 0.4064)
			(stroke
				(width 0.1524)
				(type default)
			)
			(layer "F.SilkS")
		)
		(fp_line
			(start -0.7874 -0.4064)
			(end 0.7874 -0.4064)
			(stroke
				(width 0.1524)
				(type default)
			)
			(layer "F.SilkS")
		)
		(fp_line
			(start 0.7874 -0.4064)
			(end 0.7874 0.4064)
			(stroke
				(width 0.1524)
				(type default)
			)
			(layer "F.SilkS")
		)
		(fp_line
			(start -0.67945 0.3048)
			(end -0.67945 -0.305054)
			(stroke
				(width 0.1)
				(type default)
			)
			(layer "F.Fab")
		)
		(fp_line
			(start -0.12065 0.3048)
			(end -0.67945 0.3048)
			(stroke
				(width 0.1)
				(type default)
			)
			(layer "F.Fab")
		)
		(fp_line
			(start 0.120396 0.3048)
			(end 0.120396 0.2794)
			(stroke
				(width 0.1)
				(type default)
			)
			(layer "F.Fab")
		)
		(fp_line
			(start 0.67945 0.3048)
			(end 0.120396 0.3048)
			(stroke
				(width 0.1)
				(type default)
			)
			(layer "F.Fab")
		)
		(fp_line
			(start -0.12065 0.2794)
			(end -0.12065 0.3048)
			(stroke
				(width 0.1)
				(type default)
			)
			(layer "F.Fab")
		)
		(fp_line
			(start 0.120396 0.2794)
			(end -0.12065 0.2794)
			(stroke
				(width 0.1)
				(type default)
			)
			(layer "F.Fab")
		)
		(fp_line
			(start -0.12065 -0.2794)
			(end 0.12065 -0.2794)
			(stroke
				(width 0.1)
				(type default)
			)
			(layer "F.Fab")
		)
		(fp_line
			(start 0.12065 -0.2794)
			(end 0.12065 -0.3048)
			(stroke
				(width 0.1)
				(type default)
			)
			(layer "F.Fab")
		)
		(fp_line
			(start 0.12065 -0.3048)
			(end 0.67945 -0.3048)
			(stroke
				(width 0.1)
				(type default)
			)
			(layer "F.Fab")
		)
		(fp_line
			(start 0.67945 -0.3048)
			(end 0.67945 0.3048)
			(stroke
				(width 0.1)
				(type default)
			)
			(layer "F.Fab")
		)
		(fp_line
			(start -0.67945 -0.305054)
			(end -0.12065 -0.305054)
			(stroke
				(width 0.1)
				(type default)
			)
			(layer "F.Fab")
		)
		(fp_line
			(start -0.12065 -0.305054)
			(end -0.12065 -0.2794)
			(stroke
				(width 0.1)
				(type default)
			)
			(layer "F.Fab")
		)
		(pad "1" smd circle
			(at -0.40005 0 270)
			(size 0 0)
			(layers "F.Cu" "F.Mask" "F.Paste")
			(net "RST_PEX_SYS_R_N")
		)
		(pad "2" smd circle
			(at 0.40005 0 270)
			(size 0 0)
			(layers "F.Cu" "F.Mask" "F.Paste")
			(net "P3V3_AUX")
		)
	)
	(footprint ""
		(layer "F.Cu")
		(at 460.611982 -111.531654)
		(property "Reference" "PR7061"
			(at 0 0 0)
			(layer "F.SilkS")
			(hide yes)
			(effects
				(font
					(size 1.27 1.27)
				)
			)
		)
		(property "Value" ""
			(at 0 0 0)
			(layer "F.Fab")
			(effects
				(font
					(size 1.27 1.27)
				)
			)
		)
		(duplicate_pad_numbers_are_jumpers no)
		(fp_line
			(start -0.7874 -0.4064)
			(end 0.7874 -0.4064)
			(stroke
				(width 0.1524)
				(type default)
			)
			(layer "F.SilkS")
		)
		(fp_line
			(start -0.7874 0.4064)
			(end -0.7874 -0.4064)
			(stroke
				(width 0.1524)
				(type default)
			)
			(layer "F.SilkS")
		)
		(fp_line
			(start 0.7874 -0.4064)
			(end 0.7874 0.4064)
			(stroke
				(width 0.1524)
				(type default)
			)
			(layer "F.SilkS")
		)
		(fp_line
			(start 0.7874 0.4064)
			(end -0.7874 0.4064)
			(stroke
				(width 0.1524)
				(type default)
			)
			(layer "F.SilkS")
		)
		(fp_line
			(start -0.67945 -0.305054)
			(end -0.12065 -0.305054)
			(stroke
				(width 0.1)
				(type default)
			)
			(layer "F.Fab")
		)
		(fp_line
			(start -0.67945 0.3048)
			(end -0.67945 -0.305054)
			(stroke
				(width 0.1)
				(type default)
			)
			(layer "F.Fab")
		)
		(fp_line
			(start -0.12065 -0.305054)
			(end -0.12065 -0.2794)
			(stroke
				(width 0.1)
				(type default)
			)
			(layer "F.Fab")
		)
		(fp_line
			(start -0.12065 -0.2794)
			(end 0.12065 -0.2794)
			(stroke
				(width 0.1)
				(type default)
			)
			(layer "F.Fab")
		)
		(fp_line
			(start -0.12065 0.2794)
			(end -0.12065 0.3048)
			(stroke
				(width 0.1)
				(type default)
			)
			(layer "F.Fab")
		)
		(fp_line
			(start -0.12065 0.3048)
			(end -0.67945 0.3048)
			(stroke
				(width 0.1)
				(type default)
			)
			(layer "F.Fab")
		)
		(fp_line
			(start 0.120396 0.2794)
			(end -0.12065 0.2794)
			(stroke
				(width 0.1)
				(type default)
			)
			(layer "F.Fab")
		)
		(fp_line
			(start 0.120396 0.3048)
			(end 0.120396 0.2794)
			(stroke
				(width 0.1)
				(type default)
			)
			(layer "F.Fab")
		)
		(fp_line
			(start 0.12065 -0.3048)
			(end 0.67945 -0.3048)
			(stroke
				(width 0.1)
				(type default)
			)
			(layer "F.Fab")
		)
		(fp_line
			(start 0.12065 -0.2794)
			(end 0.12065 -0.3048)
			(stroke
				(width 0.1)
				(type default)
			)
			(layer "F.Fab")
		)
		(fp_line
			(start 0.67945 -0.3048)
			(end 0.67945 0.3048)
			(stroke
				(width 0.1)
				(type default)
			)
			(layer "F.Fab")
		)
		(fp_line
			(start 0.67945 0.3048)
			(end 0.120396 0.3048)
			(stroke
				(width 0.1)
				(type default)
			)
			(layer "F.Fab")
		)
		(pad "1" smd circle
			(at -0.40005 0)
			(size 0 0)
			(layers "F.Cu" "F.Mask" "F.Paste")
			(net "P12V_NIC7_CO_ISET")
		)
		(pad "2" smd circle
			(at 0.40005 0)
			(size 0 0)
			(layers "F.Cu" "F.Mask" "F.Paste")
			(net "GND")
		)
	)
	(footprint ""
		(layer "F.Cu")
		(at 126.205488 -285.088584 90)
		(property "Reference" "PC107"
			(at 0 0 90)
			(layer "F.SilkS")
			(hide yes)
			(effects
				(font
					(size 1.27 1.27)
				)
			)
		)
		(property "Value" ""
			(at 0 0 90)
			(layer "F.Fab")
			(effects
				(font
					(size 1.27 1.27)
				)
			)
		)
		(duplicate_pad_numbers_are_jumpers no)
		(fp_line
			(start 0.7874 -0.4064)
			(end 0.7874 0.4064)
			(stroke
				(width 0.1524)
				(type default)
			)
			(layer "F.SilkS")
		)
		(fp_line
			(start -0.7874 -0.4064)
			(end 0.7874 -0.4064)
			(stroke
				(width 0.1524)
				(type default)
			)
			(layer "F.SilkS")
		)
		(fp_line
			(start 0.7874 0.4064)
			(end -0.7874 0.4064)
			(stroke
				(width 0.1524)
				(type default)
			)
			(layer "F.SilkS")
		)
		(fp_line
			(start -0.7874 0.4064)
			(end -0.7874 -0.4064)
			(stroke
				(width 0.1524)
				(type default)
			)
			(layer "F.SilkS")
		)
		(fp_line
			(start -0.12065 -0.305054)
			(end -0.12065 -0.2794)
			(stroke
				(width 0.1)
				(type default)
			)
			(layer "F.Fab")
		)
		(fp_line
			(start -0.67945 -0.305054)
			(end -0.12065 -0.305054)
			(stroke
				(width 0.1)
				(type default)
			)
			(layer "F.Fab")
		)
		(fp_line
			(start 0.67945 -0.3048)
			(end 0.67945 0.3048)
			(stroke
				(width 0.1)
				(type default)
			)
			(layer "F.Fab")
		)
		(fp_line
			(start 0.12065 -0.3048)
			(end 0.67945 -0.3048)
			(stroke
				(width 0.1)
				(type default)
			)
			(layer "F.Fab")
		)
		(fp_line
			(start 0.12065 -0.2794)
			(end 0.12065 -0.3048)
			(stroke
				(width 0.1)
				(type default)
			)
			(layer "F.Fab")
		)
		(fp_line
			(start -0.12065 -0.2794)
			(end 0.12065 -0.2794)
			(stroke
				(width 0.1)
				(type default)
			)
			(layer "F.Fab")
		)
		(fp_line
			(start 0.120396 0.2794)
			(end -0.12065 0.2794)
			(stroke
				(width 0.1)
				(type default)
			)
			(layer "F.Fab")
		)
		(fp_line
			(start -0.12065 0.2794)
			(end -0.12065 0.3048)
			(stroke
				(width 0.1)
				(type default)
			)
			(layer "F.Fab")
		)
		(fp_line
			(start 0.67945 0.3048)
			(end 0.120396 0.3048)
			(stroke
				(width 0.1)
				(type default)
			)
			(layer "F.Fab")
		)
		(fp_line
			(start 0.120396 0.3048)
			(end 0.120396 0.2794)
			(stroke
				(width 0.1)
				(type default)
			)
			(layer "F.Fab")
		)
		(fp_line
			(start -0.12065 0.3048)
			(end -0.67945 0.3048)
			(stroke
				(width 0.1)
				(type default)
			)
			(layer "F.Fab")
		)
		(fp_line
			(start -0.67945 0.3048)
			(end -0.67945 -0.305054)
			(stroke
				(width 0.1)
				(type default)
			)
			(layer "F.Fab")
		)
		(pad "1" smd circle
			(at -0.40005 0 90)
			(size 0 0)
			(layers "F.Cu" "F.Mask" "F.Paste")
			(net "P0V8_PEX1_PVCC")
		)
		(pad "2" smd circle
			(at 0.40005 0 90)
			(size 0 0)
			(layers "F.Cu" "F.Mask" "F.Paste")
			(net "GND")
		)
	)
	(footprint ""
		(layer "F.Cu")
		(at 253.489968 -72.766682 90)
		(property "Reference" "PR7076"
			(at 0 0 90)
			(layer "F.SilkS")
			(hide yes)
			(effects
				(font
					(size 1.27 1.27)
				)
			)
		)
		(property "Value" ""
			(at 0 0 90)
			(layer "F.Fab")
			(effects
				(font
					(size 1.27 1.27)
				)
			)
		)
		(duplicate_pad_numbers_are_jumpers no)
		(fp_line
			(start 0.7874 -0.4064)
			(end 0.7874 0.4064)
			(stroke
				(width 0.1524)
				(type default)
			)
			(layer "F.SilkS")
		)
		(fp_line
			(start -0.7874 -0.4064)
			(end 0.7874 -0.4064)
			(stroke
				(width 0.1524)
				(type default)
			)
			(layer "F.SilkS")
		)
		(fp_line
			(start 0.7874 0.4064)
			(end -0.7874 0.4064)
			(stroke
				(width 0.1524)
				(type default)
			)
			(layer "F.SilkS")
		)
		(fp_line
			(start -0.7874 0.4064)
			(end -0.7874 -0.4064)
			(stroke
				(width 0.1524)
				(type default)
			)
			(layer "F.SilkS")
		)
		(fp_line
			(start -0.12065 -0.305054)
			(end -0.12065 -0.2794)
			(stroke
				(width 0.1)
				(type default)
			)
			(layer "F.Fab")
		)
		(fp_line
			(start -0.67945 -0.305054)
			(end -0.12065 -0.305054)
			(stroke
				(width 0.1)
				(type default)
			)
			(layer "F.Fab")
		)
		(fp_line
			(start 0.67945 -0.3048)
			(end 0.67945 0.3048)
			(stroke
				(width 0.1)
				(type default)
			)
			(layer "F.Fab")
		)
		(fp_line
			(start 0.12065 -0.3048)
			(end 0.67945 -0.3048)
			(stroke
				(width 0.1)
				(type default)
			)
			(layer "F.Fab")
		)
		(fp_line
			(start 0.12065 -0.2794)
			(end 0.12065 -0.3048)
			(stroke
				(width 0.1)
				(type default)
			)
			(layer "F.Fab")
		)
		(fp_line
			(start -0.12065 -0.2794)
			(end 0.12065 -0.2794)
			(stroke
				(width 0.1)
				(type default)
			)
			(layer "F.Fab")
		)
		(fp_line
			(start 0.120396 0.2794)
			(end -0.12065 0.2794)
			(stroke
				(width 0.1)
				(type default)
			)
			(layer "F.Fab")
		)
		(fp_line
			(start -0.12065 0.2794)
			(end -0.12065 0.3048)
			(stroke
				(width 0.1)
				(type default)
			)
			(layer "F.Fab")
		)
		(fp_line
			(start 0.67945 0.3048)
			(end 0.120396 0.3048)
			(stroke
				(width 0.1)
				(type default)
			)
			(layer "F.Fab")
		)
		(fp_line
			(start 0.120396 0.3048)
			(end 0.120396 0.2794)
			(stroke
				(width 0.1)
				(type default)
			)
			(layer "F.Fab")
		)
		(fp_line
			(start -0.12065 0.3048)
			(end -0.67945 0.3048)
			(stroke
				(width 0.1)
				(type default)
			)
			(layer "F.Fab")
		)
		(fp_line
			(start -0.67945 0.3048)
			(end -0.67945 -0.305054)
			(stroke
				(width 0.1)
				(type default)
			)
			(layer "F.Fab")
		)
		(pad "1" smd circle
			(at -0.40005 0 90)
			(size 0 0)
			(layers "F.Cu" "F.Mask" "F.Paste")
			(net "P12V_SSD8_CO_ILIMIT")
		)
		(pad "2" smd circle
			(at 0.40005 0 90)
			(size 0 0)
			(layers "F.Cu" "F.Mask" "F.Paste")
			(net "GND")
		)
	)
	(footprint ""
		(layer "F.Cu")
		(at 166.58209 -38.041072 180)
		(property "Reference" "R6072"
			(at 0 0 180)
			(layer "F.SilkS")
			(hide yes)
			(effects
				(font
					(size 1.27 1.27)
				)
			)
		)
		(property "Value" ""
			(at 0 0 180)
			(layer "F.Fab")
			(effects
				(font
					(size 1.27 1.27)
				)
			)
		)
		(duplicate_pad_numbers_are_jumpers no)
		(fp_line
			(start 0.7874 0.4064)
			(end -0.7874 0.4064)
			(stroke
				(width 0.1524)
				(type default)
			)
			(layer "F.SilkS")
		)
		(fp_line
			(start 0.7874 -0.4064)
			(end 0.7874 0.4064)
			(stroke
				(width 0.1524)
				(type default)
			)
			(layer "F.SilkS")
		)
		(fp_line
			(start -0.7874 0.4064)
			(end -0.7874 -0.4064)
			(stroke
				(width 0.1524)
				(type default)
			)
			(layer "F.SilkS")
		)
		(fp_line
			(start -0.7874 -0.4064)
			(end 0.7874 -0.4064)
			(stroke
				(width 0.1524)
				(type default)
			)
			(layer "F.SilkS")
		)
		(fp_line
			(start 0.67945 0.3048)
			(end 0.120396 0.3048)
			(stroke
				(width 0.1)
				(type default)
			)
			(layer "F.Fab")
		)
		(fp_line
			(start 0.67945 -0.3048)
			(end 0.67945 0.3048)
			(stroke
				(width 0.1)
				(type default)
			)
			(layer "F.Fab")
		)
		(fp_line
			(start 0.12065 -0.2794)
			(end 0.12065 -0.3048)
			(stroke
				(width 0.1)
				(type default)
			)
			(layer "F.Fab")
		)
		(fp_line
			(start 0.12065 -0.3048)
			(end 0.67945 -0.3048)
			(stroke
				(width 0.1)
				(type default)
			)
			(layer "F.Fab")
		)
		(fp_line
			(start 0.120396 0.3048)
			(end 0.120396 0.2794)
			(stroke
				(width 0.1)
				(type default)
			)
			(layer "F.Fab")
		)
		(fp_line
			(start 0.120396 0.2794)
			(end -0.12065 0.2794)
			(stroke
				(width 0.1)
				(type default)
			)
			(layer "F.Fab")
		)
		(fp_line
			(start -0.12065 0.3048)
			(end -0.67945 0.3048)
			(stroke
				(width 0.1)
				(type default)
			)
			(layer "F.Fab")
		)
		(fp_line
			(start -0.12065 0.2794)
			(end -0.12065 0.3048)
			(stroke
				(width 0.1)
				(type default)
			)
			(layer "F.Fab")
		)
		(fp_line
			(start -0.12065 -0.2794)
			(end 0.12065 -0.2794)
			(stroke
				(width 0.1)
				(type default)
			)
			(layer "F.Fab")
		)
		(fp_line
			(start -0.12065 -0.305054)
			(end -0.12065 -0.2794)
			(stroke
				(width 0.1)
				(type default)
			)
			(layer "F.Fab")
		)
		(fp_line
			(start -0.67945 0.3048)
			(end -0.67945 -0.305054)
			(stroke
				(width 0.1)
				(type default)
			)
			(layer "F.Fab")
		)
		(fp_line
			(start -0.67945 -0.305054)
			(end -0.12065 -0.305054)
			(stroke
				(width 0.1)
				(type default)
			)
			(layer "F.Fab")
		)
		(pad "1" smd circle
			(at -0.40005 0 180)
			(size 0 0)
			(layers "F.Cu" "F.Mask" "F.Paste")
			(net "P5V_AUX")
		)
		(pad "2" smd circle
			(at 0.40005 0 180)
			(size 0 0)
			(layers "F.Cu" "F.Mask" "F.Paste")
			(net "P3V3_SSD6_PG_G2")
		)
	)
)
